(kicad_pcb
	(version 20260206)
	(generator "pcbnew")
	(generator_version "10.0")
	(general
		(thickness 1.6)
		(legacy_teardrops no)
	)
	(paper "A4")
	(title_block
		(title "peb — Lightning_PEB_BRD.brd")
		(comment 1 "Lightning (Wiwynn / Facebook NVMe JBOF) / footprints 120-125 of 2563")
	)
	(layers
		(0 "F.Cu" signal "TOP")
		(4 "In1.Cu" signal "L2GND")
		(6 "In2.Cu" signal "L3")
		(8 "In3.Cu" signal "L4VCC")
		(10 "In4.Cu" signal "L5VCC")
		(12 "In5.Cu" signal "L6")
		(14 "In6.Cu" signal "L7GND")
		(2 "B.Cu" signal "BOTTOM")
		(9 "F.Adhes" user "F.Adhesive")
		(11 "B.Adhes" user "B.Adhesive")
		(13 "F.Paste" user "Package Geometry/Pastemask Top")
		(15 "B.Paste" user "Package Geometry/Pastemask Bottom")
		(5 "F.SilkS" user "Ref Des/Silkscreen Top")
		(7 "B.SilkS" user "Ref Des/Silkscreen Bottom")
		(1 "F.Mask" user "Board Geometry/Soldermask Top")
		(3 "B.Mask" user "Board Geometry/Soldermask Bottom")
		(17 "Dwgs.User" user "User.Drawings")
		(19 "Cmts.User" user "User.Comments")
		(21 "Eco1.User" user "User.Eco1")
		(23 "Eco2.User" user "User.Eco2")
		(25 "Edge.Cuts" user "Board Geometry/Outline")
		(27 "Margin" user)
		(31 "F.CrtYd" user "Package Geometry/Place Bound Top")
		(29 "B.CrtYd" user "Package Geometry/Place Bound Bottom")
		(35 "F.Fab" user "Ref Des/Assembly Top")
		(33 "B.Fab" user "Ref Des/Assembly Bottom")
	)
	(footprint ""
		(layer "F.Cu")
		(at 18.7452 -56.5404 180)
		(property "Reference" "R613"
			(at 0 0 180)
			(layer "F.SilkS")
			(hide yes)
			(effects
				(font
					(size 1.27 1.27)
				)
			)
		)
		(property "Value" "0R2J-2-GP"
			(at 0.064008 -3.993896 180)
			(unlocked yes)
			(layer "F.Fab")
			(hide yes)
			(effects
				(font
					(size 1.016 1.016)
					(thickness 0.1524)
				)
			)
		)
		(property "Device Type" "R402H16"
			(at 0.064008 -5.517896 180)
			(unlocked yes)
			(layer "F.Fab")
			(hide yes)
			(effects
				(font
					(size 1.016 1.016)
					(thickness 0.1524)
				)
			)
		)
		(duplicate_pad_numbers_are_jumpers no)
		(fp_line
			(start 0.508 -0.9398)
			(end -0.508 -0.9398)
			(stroke
				(width 0.1524)
				(type default)
			)
			(layer "F.SilkS")
		)
		(fp_line
			(start -0.508 -0.9398)
			(end -0.508 0.9398)
			(stroke
				(width 0.1524)
				(type default)
			)
			(layer "F.SilkS")
		)
		(fp_rect
			(start -0.508 0.9398)
			(end 0.508 -0.9398)
			(stroke
				(width 0)
				(type default)
			)
			(fill no)
			(layer "F.CrtYd")
		)
		(fp_rect
			(start -0.508 0.9398)
			(end 0.508 -0.9398)
			(stroke
				(width 0)
				(type default)
			)
			(fill no)
			(layer "F.Fab")
		)
		(pad "1" smd custom
			(at 0 -0.4445 180)
			(size 0.1397 0.1397)
			(layers "F.Cu" "F.Mask" "F.Paste")
			(net "NIC0_MDI0_P2")
			(options
				(clearance outline)
				(anchor circle)
			)
			(primitives
				(gr_poly
					(pts
						(arc
							(start -0.1778 -0.2794)
							(mid -0.249642 -0.249642)
							(end -0.2794 -0.1778)
						)
						(arc
							(start -0.2794 0.1778)
							(mid -0.249642 0.249642)
							(end -0.1778 0.2794)
						)
						(arc
							(start 0.1778 0.2794)
							(mid 0.249642 0.249642)
							(end 0.2794 0.1778)
						)
						(arc
							(start 0.2794 -0.1778)
							(mid 0.249642 -0.249642)
							(end 0.1778 -0.2794)
						)
					)
					(width 0)
					(fill yes)
				)
			)
		)
		(pad "2" smd custom
			(at 0 0.4445 180)
			(size 0.1397 0.1397)
			(layers "F.Cu" "F.Mask" "F.Paste")
			(net "MNG_TX_DP")
			(options
				(clearance outline)
				(anchor circle)
			)
			(primitives
				(gr_poly
					(pts
						(arc
							(start -0.1778 -0.2794)
							(mid -0.249642 -0.249642)
							(end -0.2794 -0.1778)
						)
						(arc
							(start -0.2794 0.1778)
							(mid -0.249642 0.249642)
							(end -0.1778 0.2794)
						)
						(arc
							(start 0.1778 0.2794)
							(mid 0.249642 0.249642)
							(end 0.2794 0.1778)
						)
						(arc
							(start 0.2794 -0.1778)
							(mid 0.249642 -0.249642)
							(end 0.1778 -0.2794)
						)
					)
					(width 0)
					(fill yes)
				)
			)
		)
	)
	(footprint ""
		(layer "F.Cu")
		(at 234.823 -23.241)
		(property "Reference" "R808"
			(at 0 0 0)
			(layer "F.SilkS")
			(hide yes)
			(effects
				(font
					(size 1.27 1.27)
				)
			)
		)
		(property "Value" "4K7R2F-GP"
			(at 0.064008 -3.993896 0)
			(unlocked yes)
			(layer "F.Fab")
			(hide yes)
			(effects
				(font
					(size 1.016 1.016)
					(thickness 0.1524)
				)
			)
		)
		(property "Device Type" "R402H16"
			(at 0.064008 -5.517896 0)
			(unlocked yes)
			(layer "F.Fab")
			(hide yes)
			(effects
				(font
					(size 1.016 1.016)
					(thickness 0.1524)
				)
			)
		)
		(duplicate_pad_numbers_are_jumpers no)
		(fp_line
			(start -0.508 -0.9398)
			(end -0.508 0.9398)
			(stroke
				(width 0.1524)
				(type default)
			)
			(layer "F.SilkS")
		)
		(fp_line
			(start 0.508 -0.9398)
			(end -0.508 -0.9398)
			(stroke
				(width 0.1524)
				(type default)
			)
			(layer "F.SilkS")
		)
		(fp_rect
			(start -0.508 0.9398)
			(end 0.508 -0.9398)
			(stroke
				(width 0)
				(type default)
			)
			(fill no)
			(layer "F.CrtYd")
		)
		(fp_rect
			(start -0.508 0.9398)
			(end 0.508 -0.9398)
			(stroke
				(width 0)
				(type default)
			)
			(fill no)
			(layer "F.Fab")
		)
		(pad "1" smd custom
			(at 0 -0.4445)
			(size 0.1397 0.1397)
			(layers "F.Cu" "F.Mask" "F.Paste")
			(net "GND")
			(options
				(clearance outline)
				(anchor circle)
			)
			(primitives
				(gr_poly
					(pts
						(arc
							(start -0.1778 -0.2794)
							(mid -0.249642 -0.249642)
							(end -0.2794 -0.1778)
						)
						(arc
							(start -0.2794 0.1778)
							(mid -0.249642 0.249642)
							(end -0.1778 0.2794)
						)
						(arc
							(start 0.1778 0.2794)
							(mid 0.249642 0.249642)
							(end 0.2794 0.1778)
						)
						(arc
							(start 0.2794 -0.1778)
							(mid 0.249642 -0.249642)
							(end 0.1778 -0.2794)
						)
					)
					(width 0)
					(fill yes)
				)
			)
		)
		(pad "2" smd custom
			(at 0 0.4445)
			(size 0.1397 0.1397)
			(layers "F.Cu" "F.Mask" "F.Paste")
			(net "BOOTSTRAP4")
			(options
				(clearance outline)
				(anchor circle)
			)
			(primitives
				(gr_poly
					(pts
						(arc
							(start -0.1778 -0.2794)
							(mid -0.249642 -0.249642)
							(end -0.2794 -0.1778)
						)
						(arc
							(start -0.2794 0.1778)
							(mid -0.249642 0.249642)
							(end -0.1778 0.2794)
						)
						(arc
							(start 0.1778 0.2794)
							(mid 0.249642 0.249642)
							(end 0.2794 0.1778)
						)
						(arc
							(start 0.2794 -0.1778)
							(mid 0.249642 -0.249642)
							(end 0.1778 -0.2794)
						)
					)
					(width 0)
					(fill yes)
				)
			)
		)
	)
	(footprint ""
		(layer "F.Cu")
		(at 330.48448 -45.362622)
		(property "Reference" "SW5"
			(at 0 0 0)
			(layer "F.SilkS")
			(hide yes)
			(effects
				(font
					(size 1.27 1.27)
				)
			)
		)
		(property "Value" "PUSH-SW132-GP"
			(at -4.9657 -6.1341 0)
			(unlocked yes)
			(layer "F.Fab")
			(hide yes)
			(effects
				(font
					(size 1.016 1.016)
					(thickness 0.1524)
				)
			)
		)
		(property "Device Type" "PTCFGP2-Q-TR"
			(at -4.9657 -7.6581 0)
			(unlocked yes)
			(layer "F.Fab")
			(hide yes)
			(effects
				(font
					(size 1.016 1.016)
					(thickness 0.1524)
				)
			)
		)
		(duplicate_pad_numbers_are_jumpers no)
		(fp_line
			(start -3.6576 -0.6604)
			(end -3.6576 -1.0414)
			(stroke
				(width 0.3302)
				(type default)
			)
			(layer "F.SilkS")
		)
		(fp_line
			(start -3.556 -2.0066)
			(end 3.556 -2.0066)
			(stroke
				(width 0.1524)
				(type default)
			)
			(layer "F.SilkS")
		)
		(fp_line
			(start -3.556 2.0066)
			(end -3.556 -2.0066)
			(stroke
				(width 0.1524)
				(type default)
			)
			(layer "F.SilkS")
		)
		(fp_line
			(start 1.4986 2.0066)
			(end -3.556 2.0066)
			(stroke
				(width 0.1524)
				(type default)
			)
			(layer "F.SilkS")
		)
		(fp_line
			(start 1.4986 2.7686)
			(end 1.4986 2.0066)
			(stroke
				(width 0.1524)
				(type default)
			)
			(layer "F.SilkS")
		)
		(fp_line
			(start 2.7178 1.6002)
			(end 2.7178 2.7686)
			(stroke
				(width 0.1524)
				(type default)
			)
			(layer "F.SilkS")
		)
		(fp_line
			(start 2.7178 2.7686)
			(end 1.4986 2.7686)
			(stroke
				(width 0.1524)
				(type default)
			)
			(layer "F.SilkS")
		)
		(fp_line
			(start 3.556 -2.0066)
			(end 3.556 1.6002)
			(stroke
				(width 0.1524)
				(type default)
			)
			(layer "F.SilkS")
		)
		(fp_line
			(start 3.556 1.6002)
			(end 2.7178 1.6002)
			(stroke
				(width 0.1524)
				(type default)
			)
			(layer "F.SilkS")
		)
		(fp_poly
			(pts
				(xy -4.2545 -0.2159) (xy -4.2545 -1.4859) (xy -3.6195 -0.8509)
			)
			(stroke
				(width 0)
				(type default)
			)
			(fill yes)
			(layer "F.SilkS")
		)
		(fp_poly
			(pts
				(xy 1.7526 2.2606) (xy 1.7526 1.7526) (xy -2.3495 1.7526) (xy -2.3495 1.1049) (xy -2.9464 1.1049)
				(xy -2.9464 -1.1049) (xy -2.3495 -1.1049) (xy -2.3495 -1.7526) (xy 2.3495 -1.7526) (xy 2.3495 -1.1049)
				(xy 2.9464 -1.1049) (xy 2.9464 1.1049) (xy 2.3495 1.1049) (xy 2.3495 2.2606)
			)
			(stroke
				(width 0)
				(type default)
			)
			(fill no)
			(layer "F.CrtYd")
		)
		(fp_poly
			(pts
				(xy 1.2446 3.0226) (xy 1.2446 2.2606) (xy -3.81 2.2606) (xy -3.81 -2.2606) (xy -1.4097 -2.2606)
				(xy -1.4097 -1.752854) (xy -2.349754 -1.752854) (xy -2.349754 -1.105154) (xy -2.946654 -1.105154)
				(xy -2.946654 1.105154) (xy -2.349754 1.105154) (xy -2.349754 1.752854) (xy 1.752346 1.752854) (xy 1.752346 2.2606)
				(xy 2.349754 2.2606) (xy 2.349754 1.105154) (xy 2.946654 1.105154) (xy 2.946654 -1.105154) (xy 2.349754 -1.105154)
				(xy 2.349754 -1.752854) (xy -1.397 -1.752854) (xy -1.397 -2.2606) (xy 3.81 -2.2606) (xy 3.81 1.8542)
				(xy 2.9718 1.8542) (xy 2.9718 3.0226)
			)
			(stroke
				(width 0)
				(type default)
			)
			(fill no)
			(layer "F.CrtYd")
		)
		(fp_poly
			(pts
				(xy 1.2446 3.0226) (xy 1.2446 2.2606) (xy -3.81 2.2606) (xy -3.81 -2.2606) (xy 3.81 -2.2606) (xy 3.81 1.8542)
				(xy 2.9718 1.8542) (xy 2.9718 3.0226)
			)
			(stroke
				(width 0)
				(type default)
			)
			(fill no)
			(layer "F.Fab")
		)
		(pad "" np_thru_hole circle
			(at 0 -1.35001)
			(size 0.254 0.254)
			(drill 0.8128)
			(layers "*.Cu" "*.Mask")
			(clearance 0.635)
			(thermal_gap 0.635)
		)
		(pad "" np_thru_hole circle
			(at 0 1.35001)
			(size 0.254 0.254)
			(drill 0.8128)
			(layers "*.Cu" "*.Mask")
			(clearance 0.635)
			(thermal_gap 0.635)
		)
		(pad "1" smd rect
			(at -2.576068 -0.85471)
			(size 1.4478 0.9906)
			(layers "F.Cu" "F.Mask" "F.Paste")
			(net "GND")
		)
		(pad "2" smd rect
			(at -2.576068 0.85471)
			(size 1.4478 0.9906)
			(layers "F.Cu" "F.Mask" "F.Paste")
			(net "SHUTDOWN_RELEASE")
		)
		(pad "3" smd rect
			(at 2.576068 -0.85471)
			(size 1.4478 0.9906)
			(layers "F.Cu" "F.Mask" "F.Paste")
			(net "GND")
		)
		(pad "4" smd rect
			(at 2.576068 0.85471)
			(size 1.4478 0.9906)
			(layers "F.Cu" "F.Mask" "F.Paste")
			(net "SHUTDOWN_RELEASE")
		)
		(pad "5" smd rect
			(at 2.10566 2.13106)
			(size 0.7112 0.762)
			(layers "F.Cu" "F.Mask" "F.Paste")
			(net "Net_2109")
		)
		(zone
			(layers "F.Cu" "B.Cu" "In1.Cu" "In2.Cu" "In3.Cu" "In4.Cu" "In5.Cu" "In6.Cu")
			(hatch none 0.5)
			(connect_pads
				(clearance 0)
			)
			(min_thickness 0.25)
			(keepout
				(tracks not_allowed)
				(vias allowed)
				(pads allowed)
				(copperpour not_allowed)
				(footprints allowed)
			)
			(placement
				(enabled no)
				(sheetname "")
			)
			(fill
				(thermal_gap 0.5)
				(thermal_bridge_width 0.5)
				(island_removal_mode 0)
			)
			(polygon
				(pts
					(arc
						(start 331.19568 -46.712632)
						(mid 329.77328 -46.712632)
						(end 331.19568 -46.712632)
					)
				)
			)
		)
		(zone
			(layers "F.Cu" "B.Cu" "In1.Cu" "In2.Cu" "In3.Cu" "In4.Cu" "In5.Cu" "In6.Cu")
			(hatch none 0.5)
			(connect_pads
				(clearance 0)
			)
			(min_thickness 0.25)
			(keepout
				(tracks not_allowed)
				(vias allowed)
				(pads allowed)
				(copperpour not_allowed)
				(footprints allowed)
			)
			(placement
				(enabled no)
				(sheetname "")
			)
			(fill
				(thermal_gap 0.5)
				(thermal_bridge_width 0.5)
				(island_removal_mode 0)
			)
			(polygon
				(pts
					(arc
						(start 331.19568 -44.012612)
						(mid 329.77328 -44.012612)
						(end 331.19568 -44.012612)
					)
				)
			)
		)
	)
	(footprint ""
		(layer "F.Cu")
		(at 115.7732 -24.6888 180)
		(property "Reference" "R56"
			(at 0 0 180)
			(layer "F.SilkS")
			(hide yes)
			(effects
				(font
					(size 1.27 1.27)
				)
			)
		)
		(property "Value" "0R2J-2-GP"
			(at 0.064008 -3.993896 180)
			(unlocked yes)
			(layer "F.Fab")
			(hide yes)
			(effects
				(font
					(size 1.016 1.016)
					(thickness 0.1524)
				)
			)
		)
		(property "Device Type" "R402H16"
			(at 0.064008 -5.517896 180)
			(unlocked yes)
			(layer "F.Fab")
			(hide yes)
			(effects
				(font
					(size 1.016 1.016)
					(thickness 0.1524)
				)
			)
		)
		(duplicate_pad_numbers_are_jumpers no)
		(fp_line
			(start 0.508 -0.9398)
			(end -0.508 -0.9398)
			(stroke
				(width 0.1524)
				(type default)
			)
			(layer "F.SilkS")
		)
		(fp_line
			(start -0.508 -0.9398)
			(end -0.508 0.9398)
			(stroke
				(width 0.1524)
				(type default)
			)
			(layer "F.SilkS")
		)
		(fp_rect
			(start -0.508 0.9398)
			(end 0.508 -0.9398)
			(stroke
				(width 0)
				(type default)
			)
			(fill no)
			(layer "F.CrtYd")
		)
		(fp_rect
			(start -0.508 0.9398)
			(end 0.508 -0.9398)
			(stroke
				(width 0)
				(type default)
			)
			(fill no)
			(layer "F.Fab")
		)
		(pad "1" smd custom
			(at 0 -0.4445 180)
			(size 0.1397 0.1397)
			(layers "F.Cu" "F.Mask" "F.Paste")
			(net "U54_P0")
			(options
				(clearance outline)
				(anchor circle)
			)
			(primitives
				(gr_poly
					(pts
						(arc
							(start -0.1778 -0.2794)
							(mid -0.249642 -0.249642)
							(end -0.2794 -0.1778)
						)
						(arc
							(start -0.2794 0.1778)
							(mid -0.249642 0.249642)
							(end -0.1778 0.2794)
						)
						(arc
							(start 0.1778 0.2794)
							(mid 0.249642 0.249642)
							(end 0.2794 0.1778)
						)
						(arc
							(start 0.2794 -0.1778)
							(mid 0.249642 -0.249642)
							(end 0.1778 -0.2794)
						)
					)
					(width 0)
					(fill yes)
				)
			)
		)
		(pad "2" smd custom
			(at 0 0.4445 180)
			(size 0.1397 0.1397)
			(layers "F.Cu" "F.Mask" "F.Paste")
			(net "HOST_I2C_RESET_N")
			(options
				(clearance outline)
				(anchor circle)
			)
			(primitives
				(gr_poly
					(pts
						(arc
							(start -0.1778 -0.2794)
							(mid -0.249642 -0.249642)
							(end -0.2794 -0.1778)
						)
						(arc
							(start -0.2794 0.1778)
							(mid -0.249642 0.249642)
							(end -0.1778 0.2794)
						)
						(arc
							(start 0.1778 0.2794)
							(mid 0.249642 0.249642)
							(end 0.2794 0.1778)
						)
						(arc
							(start 0.2794 -0.1778)
							(mid 0.249642 -0.249642)
							(end 0.1778 -0.2794)
						)
					)
					(width 0)
					(fill yes)
				)
			)
		)
	)
	(footprint ""
		(layer "F.Cu")
		(at 273.678904 -4.639564 90)
		(property "Reference" "R222"
			(at 0 0 90)
			(layer "F.SilkS")
			(hide yes)
			(effects
				(font
					(size 1.27 1.27)
				)
			)
		)
		(property "Value" "4K7R2F-GP"
			(at 0.064008 -3.993896 90)
			(unlocked yes)
			(layer "F.Fab")
			(hide yes)
			(effects
				(font
					(size 1.016 1.016)
					(thickness 0.1524)
				)
			)
		)
		(property "Device Type" "R402H16"
			(at 0.064008 -5.517896 90)
			(unlocked yes)
			(layer "F.Fab")
			(hide yes)
			(effects
				(font
					(size 1.016 1.016)
					(thickness 0.1524)
				)
			)
		)
		(duplicate_pad_numbers_are_jumpers no)
		(fp_line
			(start 0.508 -0.9398)
			(end -0.508 -0.9398)
			(stroke
				(width 0.1524)
				(type default)
			)
			(layer "F.SilkS")
		)
		(fp_line
			(start -0.508 -0.9398)
			(end -0.508 0.9398)
			(stroke
				(width 0.1524)
				(type default)
			)
			(layer "F.SilkS")
		)
		(fp_rect
			(start -0.508 0.9398)
			(end 0.508 -0.9398)
			(stroke
				(width 0)
				(type default)
			)
			(fill no)
			(layer "F.CrtYd")
		)
		(fp_rect
			(start -0.508 0.9398)
			(end 0.508 -0.9398)
			(stroke
				(width 0)
				(type default)
			)
			(fill no)
			(layer "F.Fab")
		)
		(pad "1" smd custom
			(at 0 -0.4445 90)
			(size 0.1397 0.1397)
			(layers "F.Cu" "F.Mask" "F.Paste")
			(net "P3V3_STBY")
			(options
				(clearance outline)
				(anchor circle)
			)
			(primitives
				(gr_poly
					(pts
						(arc
							(start -0.1778 -0.2794)
							(mid -0.249642 -0.249642)
							(end -0.2794 -0.1778)
						)
						(arc
							(start -0.2794 0.1778)
							(mid -0.249642 0.249642)
							(end -0.1778 0.2794)
						)
						(arc
							(start 0.1778 0.2794)
							(mid 0.249642 0.249642)
							(end 0.2794 0.1778)
						)
						(arc
							(start 0.2794 -0.1778)
							(mid 0.249642 -0.249642)
							(end 0.1778 -0.2794)
						)
					)
					(width 0)
					(fill yes)
				)
			)
		)
		(pad "2" smd custom
			(at 0 0.4445 90)
			(size 0.1397 0.1397)
			(layers "F.Cu" "F.Mask" "F.Paste")
			(net "CLK_P_6_R")
			(options
				(clearance outline)
				(anchor circle)
			)
			(primitives
				(gr_poly
					(pts
						(arc
							(start -0.1778 -0.2794)
							(mid -0.249642 -0.249642)
							(end -0.2794 -0.1778)
						)
						(arc
							(start -0.2794 0.1778)
							(mid -0.249642 0.249642)
							(end -0.1778 0.2794)
						)
						(arc
							(start 0.1778 0.2794)
							(mid 0.249642 0.249642)
							(end 0.2794 0.1778)
						)
						(arc
							(start 0.2794 -0.1778)
							(mid 0.249642 -0.249642)
							(end 0.1778 -0.2794)
						)
					)
					(width 0)
					(fill yes)
				)
			)
		)
	)
	(footprint ""
		(layer "F.Cu")
		(at 134.932928 -59.746896 180)
		(property "Reference" "R651"
			(at 0 0 180)
			(layer "F.SilkS")
			(hide yes)
			(effects
				(font
					(size 1.27 1.27)
				)
			)
		)
		(property "Value" "100KR2F-L1-GP"
			(at 0.064008 -3.993896 180)
			(unlocked yes)
			(layer "F.Fab")
			(hide yes)
			(effects
				(font
					(size 1.016 1.016)
					(thickness 0.1524)
				)
			)
		)
		(property "Device Type" "R402H16"
			(at 0.064008 -5.517896 180)
			(unlocked yes)
			(layer "F.Fab")
			(hide yes)
			(effects
				(font
					(size 1.016 1.016)
					(thickness 0.1524)
				)
			)
		)
		(duplicate_pad_numbers_are_jumpers no)
		(fp_line
			(start 0.508 -0.9398)
			(end -0.508 -0.9398)
			(stroke
				(width 0.1524)
				(type default)
			)
			(layer "F.SilkS")
		)
		(fp_line
			(start -0.508 -0.9398)
			(end -0.508 0.9398)
			(stroke
				(width 0.1524)
				(type default)
			)
			(layer "F.SilkS")
		)
		(fp_rect
			(start -0.508 0.9398)
			(end 0.508 -0.9398)
			(stroke
				(width 0)
				(type default)
			)
			(fill no)
			(layer "F.CrtYd")
		)
		(fp_rect
			(start -0.508 0.9398)
			(end 0.508 -0.9398)
			(stroke
				(width 0)
				(type default)
			)
			(fill no)
			(layer "F.Fab")
		)
		(pad "1" smd custom
			(at 0 -0.4445 180)
			(size 0.1397 0.1397)
			(layers "F.Cu" "F.Mask" "F.Paste")
			(net "DUT_VDDO")
			(options
				(clearance outline)
				(anchor circle)
			)
			(primitives
				(gr_poly
					(pts
						(arc
							(start -0.1778 -0.2794)
							(mid -0.249642 -0.249642)
							(end -0.2794 -0.1778)
						)
						(arc
							(start -0.2794 0.1778)
							(mid -0.249642 0.249642)
							(end -0.1778 0.2794)
						)
						(arc
							(start 0.1778 0.2794)
							(mid 0.249642 0.249642)
							(end 0.2794 0.1778)
						)
						(arc
							(start 0.2794 -0.1778)
							(mid 0.249642 -0.249642)
							(end 0.1778 -0.2794)
						)
					)
					(width 0)
					(fill yes)
				)
			)
		)
		(pad "2" smd custom
			(at 0 0.4445 180)
			(size 0.1397 0.1397)
			(layers "F.Cu" "F.Mask" "F.Paste")
			(net "SPI_DATA0_2_R")
			(options
				(clearance outline)
				(anchor circle)
			)
			(primitives
				(gr_poly
					(pts
						(arc
							(start -0.1778 -0.2794)
							(mid -0.249642 -0.249642)
							(end -0.2794 -0.1778)
						)
						(arc
							(start -0.2794 0.1778)
							(mid -0.249642 0.249642)
							(end -0.1778 0.2794)
						)
						(arc
							(start 0.1778 0.2794)
							(mid 0.249642 0.249642)
							(end 0.2794 0.1778)
						)
						(arc
							(start 0.2794 -0.1778)
							(mid 0.249642 -0.249642)
							(end 0.1778 -0.2794)
						)
					)
					(width 0)
					(fill yes)
				)
			)
		)
	)
)
